# T6G (Grand Teton) — schematic netlist excerpt (pin names and nets, part order shuffled) for the footprints in the layout excerpt that follows; sources: Cadence DE-HDL packaged netlist, KiCad conversion of 04192023_DAF0TMB3IC0_F0TG_MB_C_brd_V02_OCP.brd

J20  SCONN288_DDR506112002KQ  IO  pkg DDR288S_1-1VXC  page 96
  VIN_BULK0  = P12V_MEM_CPU0
  RFU0  = NC
  VIN_MGMT  = P3V3_AUX
  HSCL  = I3C_SPD_DDRK_CPU0_SCL
  HSDA  = I3C_SPD_DDRK_CPU0_SDA
  VSS0  = GND
  DQ0_A  = M_K_CPU0_SA_DQ<0>
  VSS1  = GND
  DQ1_A  = M_K_CPU0_SA_DQ<1>
  VSS2  = GND
  DQS0_A_T  = M_K_CPU0_SA_DQS_DP<0>
  DQS0_A_C  = M_K_CPU0_SA_DQS_DN<0>
  VSS3  = GND
  DQ4_A  = M_K_CPU0_SA_DQ<4>
  VSS4  = GND
  DQ5_A  = M_K_CPU0_SA_DQ<5>
  VSS5  = GND
  DQ8_A  = M_K_CPU0_SA_DQ<8>
  VSS6  = GND
  DQ9_A  = M_K_CPU0_SA_DQ<9>
  VSS7  = GND
  DQS1_A_T  = M_K_CPU0_SA_DQS_DP<1>
  DQS1_A_C  = M_K_CPU0_SA_DQS_DN<1>
  VSS8  = GND
  DQ12_A  = M_K_CPU0_SA_DQ<12>
  VSS9  = GND
  DQ13_A  = M_K_CPU0_SA_DQ<13>
  VSS10  = GND
  DQ16_A  = M_K_CPU0_SA_DQ<16>
  VSS11  = GND
  DQ17_A  = M_K_CPU0_SA_DQ<17>
  VSS12  = GND
  DQS2_A_T  = M_K_CPU0_SA_DQS_DP<2>
  DQS2_A_C  = M_K_CPU0_SA_DQS_DN<2>
  VSS13  = GND
  DQ20_A  = M_K_CPU0_SA_DQ<20>
  VSS14  = GND
  DQ21_A  = M_K_CPU0_SA_DQ<21>
  VSS15  = GND
  DQ24_A  = M_K_CPU0_SA_DQ<24>
  VSS16  = GND
  DQ25_A  = M_K_CPU0_SA_DQ<25>
  VSS17  = GND
  DQS3_A_T  = M_K_CPU0_SA_DQS_DP<3>
  DQS3_A_C  = M_K_CPU0_SA_DQS_DN<3>
  VSS18  = GND
  DQ28_A  = M_K_CPU0_SA_DQ<28>
  VSS19  = GND
  DQ29_A  = M_K_CPU0_SA_DQ<29>
  VSS20  = GND
  CB0_A  = M_K_CPU0_SA_CB<0>
  VSS21  = GND
  CB1_A  = M_K_CPU0_SA_CB<1>
  VSS22  = GND
  DQS4_A_T  = M_K_CPU0_SA_DQS_DP<4>
  DQS4_A_C  = M_K_CPU0_SA_DQS_DN<4>
  VSS23  = GND
  CB4_A  = M_K_CPU0_SA_CB<4>
  VSS24  = GND
  CB5_A  = M_K_CPU0_SA_CB<5>
  VSS25  = GND
  ALERT_N  = M_K_CPU0_ALERT_N
  VSS26  = GND
  CS0_A_N  = M_K_CPU0_SA_CS_N<0>
  VSS27  = GND
  CA0_A  = M_K_CPU0_SA_CA<0>
  VSS28  = GND
  CA2_A  = M_K_CPU0_SA_CA<2>
  VSS29  = GND
  CA4_A  = M_K_CPU0_SA_CA<4>
  VSS30  = GND
  CA6_A  = M_K_CPU0_SA_CA<6>
  VSS31  = GND
  PAR_A  = M_K_CPU0_SA_PAR
  VSS32  = GND
  CA0_B  = M_K_CPU0_SB_CA<0>
  VSS33  = GND
  CA2_B  = M_K_CPU0_SB_CA<2>
  VSS34  = GND
  CA4_B  = M_K_CPU0_SB_CA<4>
  VSS35  = GND
  CA6_B  = M_K_CPU0_SB_CA<6>
  VSS36  = GND
  CS0_B_N  = M_K_CPU0_SB_CS_N<0>
  VSS37  = GND
  \lbd||rsp_a_n\  = M_K_CPU0_SA_RSP<0>
  \lbs||rsp_b_n\  = M_K_CPU0_SB_RSP<0>
  VSS38  = GND
  CB4_B  = M_K_CPU0_SB_CB<4>
  VSS39  = GND
  CB5_B  = M_K_CPU0_SB_CB<5>
  VSS40  = GND
  \dqs9_b_t||tdqs9_b_t||dbi4_b_n\  = M_K_CPU0_SB_DQS_DP<9>
  \dqs9_b_c||tdqs9_b_c\  = M_K_CPU0_SB_DQS_DN<9>
  VSS41  = GND
  CB0_B  = M_K_CPU0_SB_CB<0>
  VSS42  = GND
  CB1_B  = M_K_CPU0_SB_CB<1>
  VSS43  = GND
  DQ0_B  = M_K_CPU0_SB_DQ<0>
  VSS44  = GND
  DQ1_B  = M_K_CPU0_SB_DQ<1>
  VSS45  = GND
  DQS0_B_T  = M_K_CPU0_SB_DQS_DP<0>
  DQS0_B_C  = M_K_CPU0_SB_DQS_DN<0>
  VSS46  = GND
  DQ4_B  = M_K_CPU0_SB_DQ<4>
  VSS47  = GND
  DQ5_B  = M_K_CPU0_SB_DQ<5>
  VSS48  = GND
  DQ8_B  = M_K_CPU0_SB_DQ<8>
  VSS49  = GND
  DQ9_B  = M_K_CPU0_SB_DQ<9>
  VSS50  = GND
  DQS1_B_T  = M_K_CPU0_SB_DQS_DP<1>
  DQS1_B_C  = M_K_CPU0_SB_DQS_DN<1>
  VSS51  = GND
  DQ12_B  = M_K_CPU0_SB_DQ<12>
  VSS52  = GND
  DQ13_B  = M_K_CPU0_SB_DQ<13>
  VSS53  = GND
  DQ16_B  = M_K_CPU0_SB_DQ<16>
  VSS54  = GND
  DQ17_B  = M_K_CPU0_SB_DQ<17>
  VSS55  = GND
  DQS2_B_T  = M_K_CPU0_SB_DQS_DP<2>
  DQS2_B_C  = M_K_CPU0_SB_DQS_DN<2>
  VSS56  = GND
  DQ20_B  = M_K_CPU0_SB_DQ<20>
  VSS57  = GND
  DQ21_B  = M_K_CPU0_SB_DQ<21>
  VSS58  = GND
  DQ24_B  = M_K_CPU0_SB_DQ<24>
  VSS59  = GND
  DQ25_B  = M_K_CPU0_SB_DQ<25>
  VSS60  = GND
  DQS3_B_T  = M_K_CPU0_SB_DQS_DP<3>
  DQS3_B_C  = M_K_CPU0_SB_DQS_DN<3>
  VSS61  = GND
  DQ28_B  = M_K_CPU0_SB_DQ<28>
  VSS62  = GND
  DQ29_B  = M_K_CPU0_SB_DQ<29>
  VSS63  = GND
  RFU1  = NC
  VIN_BULK1  = P12V_MEM_CPU0
  VIN_BULK2  = P12V_MEM_CPU0
  \pwr_good||fail_n\  = PWRGD_CHK_CPU0_DIMM
  HAS  = PD_CHK_CPU0_DIMM_SAA
  RFU2  = NC
  RFU3  = NC
  VSS64  = GND
  DQ2_A  = M_K_CPU0_SA_DQ<2>
  VSS65  = GND
  DQ3_A  = M_K_CPU0_SA_DQ<3>
  VSS66  = GND
  \dqs5_a_c||tdqs5_a_c||dqs5_a_t||tdqs5_a_t\  = M_K_CPU0_SA_DQS_DN<5>
  \dqs5_a_t||tdqs5_a_t\  = M_K_CPU0_SA_DQS_DP<5>
  VSS67  = GND
  DQ6_A  = M_K_CPU0_SA_DQ<6>
  VSS68  = GND
  DQ7_A  = M_K_CPU0_SA_DQ<7>
  VSS69  = GND
  DQ10_A  = M_K_CPU0_SA_DQ<10>
  VSS70  = GND
  DQ11_A  = M_K_CPU0_SA_DQ<11>
  VSS71  = GND
  \dqs6_a_c||tdqs6_a_c||dqs6_a_t||tdqs6_a_t\  = M_K_CPU0_SA_DQS_DN<6>
  \dqs6_a_t||tdqs6_a_t\  = M_K_CPU0_SA_DQS_DP<6>
  VSS72  = GND
  DQ14_A  = M_K_CPU0_SA_DQ<14>
  VSS73  = GND
  DQ15_A  = M_K_CPU0_SA_DQ<15>
  VSS74  = GND
  DQ18_A  = M_K_CPU0_SA_DQ<18>
  VSS75  = GND
  DQ19_A  = M_K_CPU0_SA_DQ<19>
  VSS76  = GND
  \dqs7_a_c||tdqs7_a_c\  = M_K_CPU0_SA_DQS_DN<7>
  \dqs7_a_t||tdqs7_a_t\  = M_K_CPU0_SA_DQS_DP<7>
  VSS77  = GND
  DQ22_A  = M_K_CPU0_SA_DQ<22>
  VSS78  = GND
  DQ23_A  = M_K_CPU0_SA_DQ<23>
  VSS79  = GND
  DQ26_A  = M_K_CPU0_SA_DQ<26>
  VSS80  = GND
  DQ27_A  = M_K_CPU0_SA_DQ<27>
  VSS81  = GND
  \dqs8_a_c||tdqs8_a_c\  = M_K_CPU0_SA_DQS_DN<8>
  \dqs8_a_t||tdqs8_a_t\  = M_K_CPU0_SA_DQS_DP<8>
  VSS82  = GND
  DQ30_A  = M_K_CPU0_SA_DQ<30>
  VSS83  = GND
  DQ31_A  = M_K_CPU0_SA_DQ<31>
  VSS84  = GND
  CB2_A  = M_K_CPU0_SA_CB<2>
  VSS85  = GND
  CB3_A  = M_K_CPU0_SA_CB<3>
  VSS86  = GND
  \dqs9_a_c||tdqs9_a_c\  = M_K_CPU0_SA_DQS_DN<9>
  \dqs9_a_t||tdqs9_a_t\  = M_K_CPU0_SA_DQS_DP<9>
  VSS87  = GND
  CB6_A  = M_K_CPU0_SA_CB<6>
  VSS88  = GND
  CB7_A  = M_K_CPU0_SA_CB<7>
  VSS89  = GND
  RESET_N  = M_K_CPU0_RESET_N
  VSS90  = GND
  CS1_A_N  = M_K_CPU0_SA_CS_N<1>
  VSS91  = GND
  CA1_A  = M_K_CPU0_SA_CA<1>
  VSS92  = GND
  CA3_A  = M_K_CPU0_SA_CA<3>
  VSS93  = GND
  CA5_A  = M_K_CPU0_SA_CA<5>
  VSS94  = GND
  CK_T  = M_K_CPU0_CLK_DP<0>
  CK_C  = M_K_CPU0_CLK_DN<0>
  VSS95  = GND
  RFU4  = NC
  CA1_B  = M_K_CPU0_SB_CA<1>
  VSS96  = GND
  CA3_B  = M_K_CPU0_SB_CA<3>
  VSS97  = GND
  CA5_B  = M_K_CPU0_SB_CA<5>
  VSS98  = GND
  PAR_B  = M_K_CPU0_SB_PAR
  VSS99  = GND
  CS1_B_N  = M_K_CPU0_SB_CS_N<1>
  VSS100  = GND
  RFU5  = NC
  RFU6  = NC
  VSS101  = GND
  CB6_B  = M_K_CPU0_SB_CB<6>
  VSS102  = GND
  CB7_B  = M_K_CPU0_SB_CB<7>
  VSS103  = GND
  DQS4_B_C  = M_K_CPU0_SB_DQS_DN<4>
  DQS4_B_T  = M_K_CPU0_SB_DQS_DP<4>
  VSS104  = GND
  CB2_B  = M_K_CPU0_SB_CB<2>
  VSS105  = GND
  CB3_B  = M_K_CPU0_SB_CB<3>
  VSS106  = GND
  DQ2_B  = M_K_CPU0_SB_DQ<2>
  VSS107  = GND
  DQ3_B  = M_K_CPU0_SB_DQ<3>
  VSS108  = GND
  \dqs5_b_c||tdqs5_b_c\  = M_K_CPU0_SB_DQS_DN<5>
  \dqs5_b_t||tdqs5_b_t\  = M_K_CPU0_SB_DQS_DP<5>
  VSS109  = GND
  DQ6_B  = M_K_CPU0_SB_DQ<6>
  VSS110  = GND
  DQ7_B  = M_K_CPU0_SB_DQ<7>
  VSS111  = GND
  DQ10_B  = M_K_CPU0_SB_DQ<10>
  VSS112  = GND
  DQ11_B  = M_K_CPU0_SB_DQ<11>
  VSS113  = GND
  \dqs6_b_c||tdqs6_b_c\  = M_K_CPU0_SB_DQS_DN<6>
  \dqs6_b_t||tdqs6_b_t\  = M_K_CPU0_SB_DQS_DP<6>
  VSS114  = GND
  DQ14_B  = M_K_CPU0_SB_DQ<14>
  VSS115  = GND
  DQ15_B  = M_K_CPU0_SB_DQ<15>
  VSS116  = GND
  DQ18_B  = M_K_CPU0_SB_DQ<18>
  VSS117  = GND
  DQ19_B  = M_K_CPU0_SB_DQ<19>
  VSS118  = GND
  \dqs7_b_c||tdqs7_b_c\  = M_K_CPU0_SB_DQS_DN<7>
  \dqs7_b_t||tdqs7_b_t\  = M_K_CPU0_SB_DQS_DP<7>
  VSS119  = GND
  DQ22_B  = M_K_CPU0_SB_DQ<22>
  VSS120  = GND
  DQ23_B  = M_K_CPU0_SB_DQ<23>
  VSS121  = GND
  DQ26_B  = M_K_CPU0_SB_DQ<26>
  VSS122  = GND
  DQ27_B  = M_K_CPU0_SB_DQ<27>
  VSS123  = GND
  \dqs8_b_c||tdqs8_b_c\  = M_K_CPU0_SB_DQS_DN<8>
  \dqs8_b_t||tdqs8_b_t\  = M_K_CPU0_SB_DQS_DP<8>
  VSS124  = GND
  DQ30_B  = M_K_CPU0_SB_DQ<30>
  VSS125  = GND
  DQ31_B  = M_K_CPU0_SB_DQ<31>
  VSS126  = GND
  G1  = GND
  G2  = GND
  G3  = GND

(kicad_pcb
	(version 20260206)
	(generator "pcbnew")
	(generator_version "10.0")
	(general
		(thickness 1.6)
		(legacy_teardrops no)
	)
	(paper "A4")
	(title_block
		(title "04192023_DAF0TMB3IC0_F0TG_MB_C_brd_V02_OCP.brd")
		(comment 1 "Grand Teton / footprint 2165 of 8354 (J20), pads 47-92 of 291")
	)
	(layers
		(0 "F.Cu" signal "TOP")
		(4 "In1.Cu" signal "GND")
		(6 "In2.Cu" signal "IN1")
		(8 "In3.Cu" signal "GND1")
		(10 "In4.Cu" signal "IN2")
		(12 "In5.Cu" signal "GND2")
		(14 "In6.Cu" signal "IN3")
		(16 "In7.Cu" signal "GND3")
		(18 "In8.Cu" signal "VCC")
		(20 "In9.Cu" signal "VCC1")
		(22 "In10.Cu" signal "GND4")
		(24 "In11.Cu" signal "IN4")
		(26 "In12.Cu" signal "GND5")
		(28 "In13.Cu" signal "IN5")
		(30 "In14.Cu" signal "GND6")
		(32 "In15.Cu" signal "IN6")
		(34 "In16.Cu" signal "GND7")
		(2 "B.Cu" signal "BOTTOM")
		(9 "F.Adhes" user "F.Adhesive")
		(11 "B.Adhes" user "B.Adhesive")
		(13 "F.Paste" user "Package Geometry/Pastemask Top")
		(15 "B.Paste" user "Package Geometry/Pastemask Bottom")
		(5 "F.SilkS" user "Ref Des/Silkscreen Top")
		(7 "B.SilkS" user "Ref Des/Silkscreen Bottom")
		(1 "F.Mask" user "Board Geometry/Soldermask Top")
		(3 "B.Mask" user "Board Geometry/Soldermask Bottom")
		(17 "Dwgs.User" user "User.Drawings")
		(19 "Cmts.User" user "User.Comments")
		(21 "Eco1.User" user "User.Eco1")
		(23 "Eco2.User" user "User.Eco2")
		(25 "Edge.Cuts" user "Board Geometry/Outline")
		(27 "Margin" user)
		(31 "F.CrtYd" user "Package Geometry/Place Bound Top")
		(29 "B.CrtYd" user "Package Geometry/Place Bound Bottom")
		(35 "F.Fab" user "Ref Des/Assembly Top")
		(33 "B.Fab" user "Ref Des/Assembly Bottom")
	)
	(footprint ""
		(layer "F.Cu")
		(at 444.594234 -255.560068 180)
		(property "Reference" "J20"
			(at 1.631188 -81.796128 0)
			(unlocked yes)
			(layer "F.SilkS")
			(effects
				(font
					(size 0.7874 0.5842)
					(thickness 0.1524)
				)
			)
		)
		(property "Value" ""
			(at 0 0 180)
			(layer "F.Fab")
			(effects
				(font
					(size 1.27 1.27)
				)
			)
		)
		(duplicate_pad_numbers_are_jumpers no)
		(pad "47" smd rect
			(at -2.050034 -24.224996 90)
			(size 0.519938 1.4986)
			(layers "F.Cu" "F.Mask" "F.Paste")
			(net "M_K_CPU0_SA_DQ<28>")
		)
		(pad "48" smd rect
			(at -2.050034 -23.375112 90)
			(size 0.519938 1.4986)
			(layers "F.Cu" "F.Mask" "F.Paste")
			(net "GND")
		)
		(pad "49" smd rect
			(at -2.050034 -22.524974 90)
			(size 0.519938 1.4986)
			(layers "F.Cu" "F.Mask" "F.Paste")
			(net "M_K_CPU0_SA_DQ<29>")
		)
		(pad "50" smd rect
			(at -2.050034 -21.67509 90)
			(size 0.519938 1.4986)
			(layers "F.Cu" "F.Mask" "F.Paste")
			(net "GND")
		)
		(pad "51" smd rect
			(at -2.050034 -20.824952 90)
			(size 0.519938 1.4986)
			(layers "F.Cu" "F.Mask" "F.Paste")
			(net "M_K_CPU0_SA_CB<0>")
		)
		(pad "52" smd rect
			(at -2.050034 -19.975068 90)
			(size 0.519938 1.4986)
			(layers "F.Cu" "F.Mask" "F.Paste")
			(net "GND")
		)
		(pad "53" smd rect
			(at -2.050034 -19.12493 90)
			(size 0.519938 1.4986)
			(layers "F.Cu" "F.Mask" "F.Paste")
			(net "M_K_CPU0_SA_CB<1>")
		)
		(pad "54" smd rect
			(at -2.050034 -18.275046 90)
			(size 0.519938 1.4986)
			(layers "F.Cu" "F.Mask" "F.Paste")
			(net "GND")
		)
		(pad "55" smd rect
			(at -2.050034 -17.424908 90)
			(size 0.519938 1.4986)
			(layers "F.Cu" "F.Mask" "F.Paste")
			(net "M_K_CPU0_SA_DQS_DP<4>")
		)
		(pad "56" smd rect
			(at -2.050034 -16.575024 90)
			(size 0.519938 1.4986)
			(layers "F.Cu" "F.Mask" "F.Paste")
			(net "M_K_CPU0_SA_DQS_DN<4>")
		)
		(pad "57" smd rect
			(at -2.050034 -15.724886 90)
			(size 0.519938 1.4986)
			(layers "F.Cu" "F.Mask" "F.Paste")
			(net "GND")
		)
		(pad "58" smd rect
			(at -2.050034 -14.875002 90)
			(size 0.519938 1.4986)
			(layers "F.Cu" "F.Mask" "F.Paste")
			(net "M_K_CPU0_SA_CB<4>")
		)
		(pad "59" smd rect
			(at -2.050034 -14.025118 90)
			(size 0.519938 1.4986)
			(layers "F.Cu" "F.Mask" "F.Paste")
			(net "GND")
		)
		(pad "60" smd rect
			(at -2.050034 -13.17498 90)
			(size 0.519938 1.4986)
			(layers "F.Cu" "F.Mask" "F.Paste")
			(net "M_K_CPU0_SA_CB<5>")
		)
		(pad "61" smd rect
			(at -2.050034 -12.325096 90)
			(size 0.519938 1.4986)
			(layers "F.Cu" "F.Mask" "F.Paste")
			(net "GND")
		)
		(pad "62" smd rect
			(at -2.050034 -11.474958 90)
			(size 0.519938 1.4986)
			(layers "F.Cu" "F.Mask" "F.Paste")
			(net "M_K_CPU0_ALERT_N")
		)
		(pad "63" smd rect
			(at -2.050034 -10.625074 90)
			(size 0.519938 1.4986)
			(layers "F.Cu" "F.Mask" "F.Paste")
			(net "GND")
		)
		(pad "64" smd rect
			(at -2.050034 -9.774936 90)
			(size 0.519938 1.4986)
			(layers "F.Cu" "F.Mask" "F.Paste")
			(net "M_K_CPU0_SA_CS_N<0>")
		)
		(pad "65" smd rect
			(at -2.050034 -8.925052 90)
			(size 0.519938 1.4986)
			(layers "F.Cu" "F.Mask" "F.Paste")
			(net "GND")
		)
		(pad "66" smd rect
			(at -2.050034 -8.074914 90)
			(size 0.519938 1.4986)
			(layers "F.Cu" "F.Mask" "F.Paste")
			(net "M_K_CPU0_SA_CA<0>")
		)
		(pad "67" smd rect
			(at -2.050034 -7.22503 90)
			(size 0.519938 1.4986)
			(layers "F.Cu" "F.Mask" "F.Paste")
			(net "GND")
		)
		(pad "68" smd rect
			(at -2.050034 -6.374892 90)
			(size 0.519938 1.4986)
			(layers "F.Cu" "F.Mask" "F.Paste")
			(net "M_K_CPU0_SA_CA<2>")
		)
		(pad "69" smd rect
			(at -2.050034 -5.525008 90)
			(size 0.519938 1.4986)
			(layers "F.Cu" "F.Mask" "F.Paste")
			(net "GND")
		)
		(pad "70" smd rect
			(at -2.050034 -4.675124 90)
			(size 0.519938 1.4986)
			(layers "F.Cu" "F.Mask" "F.Paste")
			(net "M_K_CPU0_SA_CA<4>")
		)
		(pad "71" smd rect
			(at -2.050034 -3.824986 90)
			(size 0.519938 1.4986)
			(layers "F.Cu" "F.Mask" "F.Paste")
			(net "GND")
		)
		(pad "72" smd rect
			(at -2.050034 -2.975102 90)
			(size 0.519938 1.4986)
			(layers "F.Cu" "F.Mask" "F.Paste")
			(net "M_K_CPU0_SA_CA<6>")
		)
		(pad "73" smd rect
			(at -2.050034 -2.124964 90)
			(size 0.519938 1.4986)
			(layers "F.Cu" "F.Mask" "F.Paste")
			(net "GND")
		)
		(pad "74" smd rect
			(at -2.050034 -1.27508 90)
			(size 0.519938 1.4986)
			(layers "F.Cu" "F.Mask" "F.Paste")
			(net "M_K_CPU0_SA_PAR")
		)
		(pad "75" smd rect
			(at -2.050034 -0.424942 90)
			(size 0.519938 1.4986)
			(layers "F.Cu" "F.Mask" "F.Paste")
			(net "GND")
		)
		(pad "76" smd rect
			(at -2.050034 5.525008 90)
			(size 0.519938 1.4986)
			(layers "F.Cu" "F.Mask" "F.Paste")
			(net "M_K_CPU0_SB_CA<0>")
		)
		(pad "77" smd rect
			(at -2.050034 6.374892 90)
			(size 0.519938 1.4986)
			(layers "F.Cu" "F.Mask" "F.Paste")
			(net "GND")
		)
		(pad "78" smd rect
			(at -2.050034 7.22503 90)
			(size 0.519938 1.4986)
			(layers "F.Cu" "F.Mask" "F.Paste")
			(net "M_K_CPU0_SB_CA<2>")
		)
		(pad "79" smd rect
			(at -2.050034 8.074914 90)
			(size 0.519938 1.4986)
			(layers "F.Cu" "F.Mask" "F.Paste")
			(net "GND")
		)
		(pad "80" smd rect
			(at -2.050034 8.925052 90)
			(size 0.519938 1.4986)
			(layers "F.Cu" "F.Mask" "F.Paste")
			(net "M_K_CPU0_SB_CA<4>")
		)
		(pad "81" smd rect
			(at -2.050034 9.774936 90)
			(size 0.519938 1.4986)
			(layers "F.Cu" "F.Mask" "F.Paste")
			(net "GND")
		)
		(pad "82" smd rect
			(at -2.050034 10.625074 90)
			(size 0.519938 1.4986)
			(layers "F.Cu" "F.Mask" "F.Paste")
			(net "M_K_CPU0_SB_CA<6>")
		)
		(pad "83" smd rect
			(at -2.050034 11.474958 90)
			(size 0.519938 1.4986)
			(layers "F.Cu" "F.Mask" "F.Paste")
			(net "GND")
		)
		(pad "84" smd rect
			(at -2.050034 12.325096 90)
			(size 0.519938 1.4986)
			(layers "F.Cu" "F.Mask" "F.Paste")
			(net "M_K_CPU0_SB_CS_N<0>")
		)
		(pad "85" smd rect
			(at -2.050034 13.17498 90)
			(size 0.519938 1.4986)
			(layers "F.Cu" "F.Mask" "F.Paste")
			(net "GND")
		)
		(pad "86" smd rect
			(at -2.050034 14.025118 90)
			(size 0.519938 1.4986)
			(layers "F.Cu" "F.Mask" "F.Paste")
			(net "M_K_CPU0_SA_RSP<0>")
		)
		(pad "87" smd rect
			(at -2.050034 14.875002 90)
			(size 0.519938 1.4986)
			(layers "F.Cu" "F.Mask" "F.Paste")
			(net "M_K_CPU0_SB_RSP<0>")
		)
		(pad "88" smd rect
			(at -2.050034 15.724886 90)
			(size 0.519938 1.4986)
			(layers "F.Cu" "F.Mask" "F.Paste")
			(net "GND")
		)
		(pad "89" smd rect
			(at -2.050034 16.575024 90)
			(size 0.519938 1.4986)
			(layers "F.Cu" "F.Mask" "F.Paste")
			(net "M_K_CPU0_SB_CB<4>")
		)
		(pad "90" smd rect
			(at -2.050034 17.424908 90)
			(size 0.519938 1.4986)
			(layers "F.Cu" "F.Mask" "F.Paste")
			(net "GND")
		)
		(pad "91" smd rect
			(at -2.050034 18.275046 90)
			(size 0.519938 1.4986)
			(layers "F.Cu" "F.Mask" "F.Paste")
			(net "M_K_CPU0_SB_CB<5>")
		)
		(pad "92" smd rect
			(at -2.050034 19.12493 90)
			(size 0.519938 1.4986)
			(layers "F.Cu" "F.Mask" "F.Paste")
			(net "GND")
		)
	)
)
